#ISCELL
  pure_quanta quanta_title_block_c *
  *
#CELL
  pure_quanta tp_tdr_4p_fts *
  page288_i10
#ISCELL
  logical_power universal_gnd *
  page288_i100
#CELL
  pure_quanta tdr_3p *
  page288_i101
#ISCELL
  logical_power universal_gnd *
  page288_i102
#ISCELL
  logical_power universal_gnd *
  page288_i103
#ISCELL
  logical_power universal_gnd *
  page288_i104
#ISCELL
  logical_power universal_gnd *
  page288_i105
#CELL
  pure_quanta tp_tdr_4p_fts *
  page288_i106
#CELL
  pure_quanta tp_tdr_4p_fts *
  page288_i107
#CELL
  pure_quanta tp_tdr_4p_fts *
  page288_i108
#ISCELL
  logical_power universal_gnd *
  page288_i109
#CELL
  pure_quanta tp_tdr_4p_fts *
  page288_i11
#CELL
  pure_quanta tp_tdr_4p_fts *
  page288_i110
#ISCELL
  logical_power universal_gnd *
  page288_i111
#CELL
  pure_quanta tp_tdr_4p_fts *
  page288_i112
#ISCELL
  logical_power universal_gnd *
  page288_i113
#ISCELL
  logical_power universal_gnd *
  page288_i114
#CELL
  pure_quanta tp_tdr_4p_fts *
  page288_i115
#CELL
  pure_quanta tp_tdr_4p_fts *
  page288_i116
#CELL
  pure_quanta tp_tdr_4p_fts *
  page288_i117
#ISCELL
  logical_power universal_gnd *
  page288_i118
#ISCELL
  logical_power universal_gnd *
  page288_i119
#CELL
  pure_quanta tp_tdr_4p_fts *
  page288_i12
#ISCELL
  logical_power universal_gnd *
  page288_i13
#CELL
  pure_quanta tp_tdr_4p_fts *
  page288_i17
#CELL
  pure_quanta tp_tdr_4p_fts *
  page288_i18
#CELL
  pure_quanta tp_tdr_4p_fts *
  page288_i19
#CELL
  pure_quanta tp_tdr_4p_fts *
  page288_i26
#CELL
  pure_quanta tp_tdr_4p_fts *
  page288_i27
#CELL
  pure_quanta tp_tdr_4p_fts *
  page288_i28
#CELL
  pure_quanta tp_tdr_4p_fts *
  page288_i3
#CELL
  pure_quanta tp_tdr_4p_fts *
  page288_i30
#CELL
  pure_quanta tp_tdr_4p_fts *
  page288_i32
#CELL
  pure_quanta tp_tdr_4p_fts *
  page288_i33
#CELL
  pure_quanta tp_tdr_4p_fts *
  page288_i34
#CELL
  pure_quanta tp_tdr_4p_fts *
  page288_i35
#CELL
  pure_quanta tp_tdr_4p_fts *
  page288_i37
#CELL
  pure_quanta tp_tdr_4p_fts *
  page288_i39
#CELL
  pure_quanta tp_tdr_4p_fts *
  page288_i4
#CELL
  pure_quanta tp_tdr_4p_fts *
  page288_i42
#CELL
  pure_quanta tp_tdr_4p_fts *
  page288_i43
#CELL
  pure_quanta tp_tdr_4p_fts *
  page288_i46
#CELL
  pure_quanta tp_tdr_4p_fts *
  page288_i47
#CELL
  pure_quanta tdr_3p *
  page288_i49
#ISCELL
  logical_power universal_gnd *
  page288_i50
#CELL
  pure_quanta tdr_3p *
  page288_i51
#ISCELL
  logical_power universal_gnd *
  page288_i52
#CELL
  pure_quanta tdr_3p *
  page288_i53
#ISCELL
  logical_power universal_gnd *
  page288_i54
#CELL
  pure_quanta tdr_3p *
  page288_i55
#ISCELL
  logical_power universal_gnd *
  page288_i56
#CELL
  pure_quanta tdr_3p *
  page288_i57
#ISCELL
  logical_power universal_gnd *
  page288_i58
#ISCELL
  logical_power universal_gnd *
  page288_i59
#CELL
  pure_quanta tdr_3p *
  page288_i60
#CELL
  pure_quanta tdr_3p *
  page288_i61
#CELL
  pure_quanta tdr_3p *
  page288_i62
#CELL
  pure_quanta tdr_3p *
  page288_i63
#ISCELL
  logical_power universal_gnd *
  page288_i64
#ISCELL
  logical_power universal_gnd *
  page288_i65
#ISCELL
  logical_power universal_gnd *
  page288_i66
#CELL
  pure_quanta tdr_3p *
  page288_i67
#CELL
  pure_quanta tdr_3p *
  page288_i68
#CELL
  pure_quanta tdr_3p *
  page288_i69
#ISCELL
  logical_power universal_gnd *
  page288_i70
#ISCELL
  logical_power universal_gnd *
  page288_i71
#ISCELL
  logical_power universal_gnd *
  page288_i72
#ISCELL
  logical_power universal_gnd *
  page288_i73
#ISCELL
  logical_power universal_gnd *
  page288_i74
#ISCELL
  logical_power universal_gnd *
  page288_i75
#ISCELL
  logical_power universal_gnd *
  page288_i76
#ISCELL
  logical_power universal_gnd *
  page288_i77
#ISCELL
  logical_power universal_gnd *
  page288_i78
#ISCELL
  logical_power universal_gnd *
  page288_i79
#CELL
  pure_quanta tp_tdr_4p_fts *
  page288_i8
#ISCELL
  logical_power universal_gnd *
  page288_i80
#ISCELL
  logical_power universal_gnd *
  page288_i81
#ISCELL
  logical_power universal_gnd *
  page288_i82
#ISCELL
  logical_power universal_gnd *
  page288_i83
#ISCELL
  logical_power universal_gnd *
  page288_i84
#ISCELL
  logical_power universal_gnd *
  page288_i85
#ISCELL
  logical_power universal_gnd *
  page288_i86
#ISCELL
  logical_power universal_gnd *
  page288_i87
#ISCELL
  logical_power universal_gnd *
  page288_i88
#ISCELL
  logical_power universal_gnd *
  page288_i89
#CELL
  pure_quanta tp_tdr_4p_fts *
  page288_i9
#ISCELL
  logical_power universal_gnd *
  page288_i90
#ISCELL
  logical_power universal_gnd *
  page288_i91
#ISCELL
  logical_power universal_gnd *
  page288_i92
#ISCELL
  logical_power universal_gnd *
  page288_i93
#ISCELL
  logical_power universal_gnd *
  page288_i94
#ISCELL
  logical_power universal_gnd *
  page288_i95
#CELL
  pure_quanta tdr_3p *
  page288_i96
#CELL
  pure_quanta tdr_3p *
  page288_i97
#ISCELL
  logical_power universal_gnd *
  page288_i98
#CELL
  pure_quanta tdr_3p *
  page288_i99
